(kicad_pcb
	(version 20241229)
	(generator "pcbnew")
	(generator_version "9.0")
	(general
		(thickness 1.62)
		(legacy_teardrops no)
	)
	(paper "A3")
	(title_block
		(title "COM Express 7 Baseboard")
		(date "2025-02-04")
		(rev "1.1.2")
		(company "Antmicro Ltd")
		(comment 1 "www.antmicro.com")
		(comment 9 "footprints 254-257 of 802")
	)
	(layers
		(0 "F.Cu" signal)
		(4 "In1.Cu" signal)
		(6 "In2.Cu" signal)
		(8 "In3.Cu" signal)
		(10 "In4.Cu" signal)
		(12 "In5.Cu" signal)
		(14 "In6.Cu" signal)
		(2 "B.Cu" signal)
		(9 "F.Adhes" user "F.Adhesive")
		(11 "B.Adhes" user "B.Adhesive")
		(13 "F.Paste" user)
		(15 "B.Paste" user)
		(5 "F.SilkS" user "F.Silkscreen")
		(7 "B.SilkS" user "B.Silkscreen")
		(1 "F.Mask" user)
		(3 "B.Mask" user)
		(17 "Dwgs.User" user "User.Drawings")
		(19 "Cmts.User" user "User.Comments")
		(21 "Eco1.User" user "User.Eco1")
		(23 "Eco2.User" user "User.Eco2")
		(25 "Edge.Cuts" user)
		(27 "Margin" user)
		(31 "F.CrtYd" user "F.Courtyard")
		(29 "B.CrtYd" user "B.Courtyard")
		(35 "F.Fab" user)
		(33 "B.Fab" user)
	)
	(footprint "antmicro-footprints:C_0603_1608Metric"
		(layer "F.Cu")
		(at 177.52 97.05)
		(descr "Capacitor SMD 0603")
		(tags "capacitor 0603")
		(property "Reference" "C73"
			(at -3.32 0.46 0)
			(layer "F.SilkS")
			(effects
				(font
					(size 0.7 0.7)
					(thickness 0.15)
				)
				(justify left bottom)
			)
		)
		(property "Value" "C_22u_16V_0603"
			(at -1.42757 1.770288 0)
			(layer "F.Fab")
			(effects
				(font
					(size 0.7 0.7)
					(thickness 0.15)
				)
				(justify left bottom)
			)
		)
		(property "Datasheet" "https://product.samsungsem.com/mlcc/CL10A226MO7JZN.do"
			(at 0 0 0)
			(layer "F.Fab")
			(hide yes)
			(effects
				(font
					(size 1.27 1.27)
					(thickness 0.15)
				)
			)
		)
		(property "Author" "Antmicro"
			(at 0 0 0)
			(layer "F.Fab")
			(hide yes)
			(effects
				(font
					(size 1 1)
					(thickness 0.15)
				)
			)
		)
		(property "Dielectric" ""
			(at 0 0 0)
			(layer "F.Fab")
			(hide yes)
			(effects
				(font
					(size 1 1)
					(thickness 0.15)
				)
			)
		)
		(property "License" "Apache-2.0"
			(at 0 0 0)
			(layer "F.Fab")
			(hide yes)
			(effects
				(font
					(size 1 1)
					(thickness 0.15)
				)
			)
		)
		(property "MPN" "CL10A226MO7JZNC"
			(at 0 0 0)
			(layer "F.Fab")
			(hide yes)
			(effects
				(font
					(size 1 1)
					(thickness 0.15)
				)
			)
		)
		(property "Manufacturer" "Samsung Electro-Mechanics"
			(at 0 0 0)
			(layer "F.Fab")
			(hide yes)
			(effects
				(font
					(size 1 1)
					(thickness 0.15)
				)
			)
		)
		(property "Public" "False"
			(at 0 0 0)
			(layer "F.Fab")
			(hide yes)
			(effects
				(font
					(size 1 1)
					(thickness 0.15)
				)
			)
		)
		(property "Val" "22u"
			(at 0 0 0)
			(layer "F.Fab")
			(hide yes)
			(effects
				(font
					(size 1 1)
					(thickness 0.15)
				)
			)
		)
		(property "Voltage" "16V"
			(at 0 0 0)
			(layer "F.Fab")
			(hide yes)
			(effects
				(font
					(size 1 1)
					(thickness 0.15)
				)
			)
		)
		(sheetname "M.2 key M #1")
		(sheetfile "m2keym_low.kicad_sch")
		(attr smd)
		(fp_line
			(start -0.15 -0.4)
			(end 0.15 -0.4)
			(stroke
				(width 0.15)
				(type solid)
			)
			(layer "F.SilkS")
		)
		(fp_line
			(start -0.15 0.4)
			(end 0.15 0.4)
			(stroke
				(width 0.15)
				(type solid)
			)
			(layer "F.SilkS")
		)
		(fp_rect
			(start -1.25 -0.65)
			(end 1.25 0.65)
			(stroke
				(width 0.05)
				(type solid)
			)
			(fill no)
			(layer "F.CrtYd")
		)
		(fp_rect
			(start -0.8 -0.4)
			(end 0.8 0.4)
			(stroke
				(width 0.15)
				(type solid)
			)
			(fill no)
			(layer "F.Fab")
		)
		(pad "1" smd roundrect
			(at -0.7 0)
			(size 0.8 1)
			(layers "F.Cu" "F.Mask" "F.Paste")
			(roundrect_rratio 0.2)
			(net 1 "GND")
			(pintype "passive")
			(teardrops
				(best_length_ratio 0.2)
				(max_length 1)
				(best_width_ratio 0.9)
				(max_width 2)
				(curved_edges yes)
				(filter_ratio 0.9)
				(enabled yes)
				(allow_two_segments yes)
				(prefer_zone_connections yes)
			)
		)
		(pad "2" smd roundrect
			(at 0.7 0)
			(size 0.8 1)
			(layers "F.Cu" "F.Mask" "F.Paste")
			(roundrect_rratio 0.2)
			(net 969 "/M.2 key M #1/M2_3V3")
			(pintype "passive")
			(teardrops
				(best_length_ratio 0.2)
				(max_length 1)
				(best_width_ratio 0.9)
				(max_width 2)
				(curved_edges yes)
				(filter_ratio 0.9)
				(enabled yes)
				(allow_two_segments yes)
				(prefer_zone_connections yes)
			)
		)
	)
	(footprint "antmicro-footprints:Vishay_PowerPAK_1212-8_Single"
		(layer "F.Cu")
		(at 306.125 142.285 180)
		(descr "PowerPAK 1212-8 Single")
		(tags "Vishay PowerPAK 1212-8 Single")
		(property "Reference" "Q2"
			(at 2.125 -0.275 90)
			(layer "F.SilkS")
			(effects
				(font
					(size 0.7 0.7)
					(thickness 0.15)
				)
				(justify right bottom)
			)
		)
		(property "Value" "SI7613DN-T1-GE3"
			(at 0 2.7 0)
			(layer "F.Fab")
			(effects
				(font
					(size 0.7 0.7)
					(thickness 0.15)
				)
				(justify right bottom)
			)
		)
		(property "Datasheet" "https://www.vishay.com/docs/64809/si7613dn.pdf"
			(at 0 0 180)
			(layer "F.Fab")
			(hide yes)
			(effects
				(font
					(size 1.27 1.27)
					(thickness 0.15)
				)
			)
		)
		(property "Author" "Antmicro"
			(at 612.25 284.57 0)
			(layer "F.Fab")
			(hide yes)
			(effects
				(font
					(size 1 1)
					(thickness 0.15)
				)
			)
		)
		(property "License" "Apache-2.0"
			(at 612.25 284.57 0)
			(layer "F.Fab")
			(hide yes)
			(effects
				(font
					(size 1 1)
					(thickness 0.15)
				)
			)
		)
		(property "MPN" "SI7613DN-T1-GE3"
			(at 612.25 284.57 0)
			(layer "F.Fab")
			(hide yes)
			(effects
				(font
					(size 1 1)
					(thickness 0.15)
				)
			)
		)
		(property "Manufacturer" "Vishay"
			(at 612.25 284.57 0)
			(layer "F.Fab")
			(hide yes)
			(effects
				(font
					(size 1 1)
					(thickness 0.15)
				)
			)
		)
		(sheetname "Power")
		(sheetfile "power.kicad_sch")
		(attr smd)
		(fp_line
			(start 1.648 -1.651)
			(end 1.648 -1.317)
			(stroke
				(width 0.15)
				(type solid)
			)
			(layer "F.SilkS")
		)
		(fp_line
			(start 1.634 1.3)
			(end 1.634 1.634)
			(stroke
				(width 0.15)
				(type solid)
			)
			(layer "F.SilkS")
		)
		(fp_line
			(start -1.635 1.634)
			(end 1.634 1.634)
			(stroke
				(width 0.15)
				(type solid)
			)
			(layer "F.SilkS")
		)
		(fp_line
			(start -1.635 1.3)
			(end -1.635 1.634)
			(stroke
				(width 0.15)
				(type solid)
			)
			(layer "F.SilkS")
		)
		(fp_line
			(start -1.651 -1.651)
			(end 1.648 -1.651)
			(stroke
				(width 0.15)
				(type solid)
			)
			(layer "F.SilkS")
		)
		(fp_line
			(start -1.651 -1.651)
			(end -1.651 -1.317)
			(stroke
				(width 0.15)
				(type solid)
			)
			(layer "F.SilkS")
		)
		(fp_circle
			(center -1.9 -1.4)
			(end -1.85 -1.4)
			(stroke
				(width 0.15)
				(type solid)
			)
			(fill yes)
			(layer "F.SilkS")
		)
		(fp_rect
			(start -2 -1.8)
			(end 2 1.798)
			(stroke
				(width 0.05)
				(type solid)
			)
			(fill no)
			(layer "F.CrtYd")
		)
		(fp_line
			(start -1.6425 -1.4175)
			(end -1.4175 -1.6425)
			(stroke
				(width 0.15)
				(type solid)
			)
			(layer "F.Fab")
		)
		(fp_rect
			(start -1.651 -1.651)
			(end 1.648 1.648)
			(stroke
				(width 0.15)
				(type solid)
			)
			(fill no)
			(layer "F.Fab")
		)
		(pad "1" smd rect
			(at -1.436 -0.99 180)
			(size 0.99 0.405)
			(layers "F.Cu" "F.Mask" "F.Paste")
			(net 62 "+12V_AON")
			(pinfunction "S")
			(pintype "passive")
			(teardrops
				(best_length_ratio 0.2)
				(max_length 1)
				(best_width_ratio 0.9)
				(max_width 2)
				(curved_edges yes)
				(filter_ratio 0.9)
				(enabled yes)
				(allow_two_segments yes)
				(prefer_zone_connections yes)
			)
		)
		(pad "2" smd rect
			(at -1.436 -0.332 180)
			(size 0.99 0.405)
			(layers "F.Cu" "F.Mask" "F.Paste")
			(net 62 "+12V_AON")
			(pinfunction "S")
			(pintype "passive")
			(teardrops
				(best_length_ratio 0.2)
				(max_length 1)
				(best_width_ratio 0.9)
				(max_width 2)
				(curved_edges yes)
				(filter_ratio 0.9)
				(enabled yes)
				(allow_two_segments yes)
				(prefer_zone_connections yes)
			)
		)
		(pad "3" smd rect
			(at -1.436 0.33 180)
			(size 0.99 0.405)
			(layers "F.Cu" "F.Mask" "F.Paste")
			(net 62 "+12V_AON")
			(pinfunction "S")
			(pintype "passive")
			(teardrops
				(best_length_ratio 0.2)
				(max_length 1)
				(best_width_ratio 0.9)
				(max_width 2)
				(curved_edges yes)
				(filter_ratio 0.9)
				(enabled yes)
				(allow_two_segments yes)
				(prefer_zone_connections yes)
			)
		)
		(pad "4" smd rect
			(at -1.436 0.988 180)
			(size 0.99 0.405)
			(layers "F.Cu" "F.Mask" "F.Paste")
			(net 534 "Net-(Q1-D)")
			(pinfunction "G")
			(pintype "passive")
			(teardrops
				(best_length_ratio 0.2)
				(max_length 1)
				(best_width_ratio 0.9)
				(max_width 2)
				(curved_edges yes)
				(filter_ratio 0.9)
				(enabled yes)
				(allow_two_segments yes)
				(prefer_zone_connections yes)
			)
		)
		(pad "5" smd custom
			(at 0.557 0 180)
			(size 1.725 2.235)
			(layers "F.Cu" "F.Mask" "F.Paste")
			(net 65 "+12V")
			(pinfunction "D")
			(pintype "passive")
			(zone_connect 2)
			(options
				(clearance outline)
				(anchor rect)
			)
			(primitives
				(gr_poly
					(pts
						(xy 0.8625 0.1275) (xy 0.8625 -0.1275) (xy 1.3725 -0.1275) (xy 1.3725 -0.5325) (xy 0.8625 -0.5325)
						(xy 0.8625 -0.7875) (xy 1.3725 -0.7875) (xy 1.3725 -1.195) (xy 0.6125 -1.195) (xy 0.6125 1.195)
						(xy 1.3725 1.195) (xy 1.3725 0.7875) (xy 0.8625 0.7875) (xy 0.8625 0.5325) (xy 1.3725 0.5325)
						(xy 1.3725 0.1275)
					)
					(width 0)
					(fill yes)
				)
			)
			(teardrops
				(best_length_ratio 0.2)
				(max_length 1)
				(best_width_ratio 0.9)
				(max_width 2)
				(curved_edges yes)
				(filter_ratio 0.9)
				(enabled yes)
				(allow_two_segments yes)
				(prefer_zone_connections yes)
			)
		)
	)
	(footprint "antmicro-footprints:TP_SMD_0.75mm"
		(layer "F.Cu")
		(at 134.29 129.56)
		(property "Reference" "TP82"
			(at 0.46 -1.25 90)
			(layer "F.SilkS")
			(effects
				(font
					(size 0.7 0.7)
					(thickness 0.15)
				)
				(justify left bottom)
			)
		)
		(property "Value" "TP_0.75mm_SMD"
			(at 0 1.2 0)
			(layer "F.Fab")
			(effects
				(font
					(size 0.7 0.7)
					(thickness 0.15)
				)
				(justify left bottom)
			)
		)
		(property "Author" "Antmicro"
			(at 0 0 0)
			(layer "F.Fab")
			(hide yes)
			(effects
				(font
					(size 1 1)
					(thickness 0.15)
				)
			)
		)
		(property "License" "Apache-2.0"
			(at 0 0 0)
			(layer "F.Fab")
			(hide yes)
			(effects
				(font
					(size 1 1)
					(thickness 0.15)
				)
			)
		)
		(property "MPN" ""
			(at 0 0 0)
			(layer "F.Fab")
			(hide yes)
			(effects
				(font
					(size 1 1)
					(thickness 0.15)
				)
			)
		)
		(property "Manufacturer" ""
			(at 0 0 0)
			(layer "F.Fab")
			(hide yes)
			(effects
				(font
					(size 1 1)
					(thickness 0.15)
				)
			)
		)
		(property "Public" "False"
			(at 0 0 0)
			(layer "F.Fab")
			(hide yes)
			(effects
				(font
					(size 1 1)
					(thickness 0.15)
				)
			)
		)
		(sheetname "KR to SFI #2")
		(sheetfile "kr_sfi.kicad_sch")
		(attr exclude_from_pos_files exclude_from_bom)
		(fp_circle
			(center 0 0)
			(end 0.475 0)
			(stroke
				(width 0.05)
				(type default)
			)
			(fill no)
			(layer "F.CrtYd")
		)
		(pad "1" smd circle
			(at 0 0)
			(size 0.75 0.75)
			(layers "F.Cu" "F.Mask")
			(net 745 "/2xSFP+/KR to SFI #2/TCK")
			(pinfunction "1")
			(pintype "passive")
			(teardrops
				(best_length_ratio 0.4)
				(max_length 1)
				(best_width_ratio 0.9)
				(max_width 2)
				(curved_edges yes)
				(filter_ratio 0.9)
				(enabled yes)
				(allow_two_segments yes)
				(prefer_zone_connections yes)
			)
		)
	)
	(footprint "antmicro-footprints:USON-10_2.5x1mm_P0.5mm"
		(layer "F.Cu")
		(at 314.75 160.91)
		(descr "USON-10 2.5x1mm_ Pitch 0.5mm")
		(tags "USON-10 2.5x1mm Pitch 0.5mm")
		(property "Reference" "U16"
			(at -0.9 1.1 90)
			(layer "F.SilkS")
			(effects
				(font
					(size 0.7 0.7)
					(thickness 0.15)
				)
				(justify left bottom)
			)
		)
		(property "Value" "ESD204DQAR"
			(at 0.018 2.499 0)
			(layer "F.Fab")
			(effects
				(font
					(size 0.7 0.7)
					(thickness 0.15)
				)
				(justify left bottom)
			)
		)
		(property "Datasheet" "https://www.ti.com/lit/ds/symlink/esd204.pdf?ts=1706004844383&ref_url=https%253A%252F%252Fwww.ti.com%252Finterface%252Fdiodes%252Fesd-protection-diodes%252Fproducts.html"
			(at 0 0 0)
			(layer "F.Fab")
			(hide yes)
			(effects
				(font
					(size 1.27 1.27)
					(thickness 0.15)
				)
			)
		)
		(property "Author" "Antmicro"
			(at 0 0 0)
			(layer "F.Fab")
			(hide yes)
			(effects
				(font
					(size 1 1)
					(thickness 0.15)
				)
			)
		)
		(property "License" "Apache-2.0"
			(at 0 0 0)
			(layer "F.Fab")
			(hide yes)
			(effects
				(font
					(size 1 1)
					(thickness 0.15)
				)
			)
		)
		(property "MPN" "ESD204DQAR"
			(at 0 0 0)
			(layer "F.Fab")
			(hide yes)
			(effects
				(font
					(size 1 1)
					(thickness 0.15)
				)
			)
		)
		(property "Manufacturer" "Texas Instruments"
			(at 0 0 0)
			(layer "F.Fab")
			(hide yes)
			(effects
				(font
					(size 1 1)
					(thickness 0.15)
				)
			)
		)
		(sheetname "Backplane")
		(sheetfile "backplane.kicad_sch")
		(attr smd)
		(fp_line
			(start 0.498 -1.401)
			(end -0.5 -1.401)
			(stroke
				(width 0.15)
				(type solid)
			)
			(layer "F.SilkS")
		)
		(fp_line
			(start 0.498 1.398)
			(end -0.5 1.398)
			(stroke
				(width 0.15)
				(type solid)
			)
			(layer "F.SilkS")
		)
		(fp_circle
			(center -0.68 -1.27)
			(end -0.63 -1.27)
			(stroke
				(width 0.15)
				(type solid)
			)
			(fill yes)
			(layer "F.SilkS")
		)
		(fp_rect
			(start -0.8 -1.5)
			(end 0.8 1.499)
			(stroke
				(width 0.05)
				(type solid)
			)
			(fill no)
			(layer "F.CrtYd")
		)
		(fp_line
			(start -0.5 -1)
			(end -0.5 1.249)
			(stroke
				(width 0.15)
				(type solid)
			)
			(layer "F.Fab")
		)
		(fp_line
			(start -0.5 1.249)
			(end 0.498 1.249)
			(stroke
				(width 0.15)
				(type solid)
			)
			(layer "F.Fab")
		)
		(fp_line
			(start -0.25 -1.25)
			(end -0.5 -1)
			(stroke
				(width 0.15)
				(type solid)
			)
			(layer "F.Fab")
		)
		(fp_line
			(start 0.498 -1.25)
			(end -0.25 -1.25)
			(stroke
				(width 0.15)
				(type solid)
			)
			(layer "F.Fab")
		)
		(fp_line
			(start 0.498 -1.25)
			(end 0.498 1.249)
			(stroke
				(width 0.15)
				(type solid)
			)
			(layer "F.Fab")
		)
		(pad "1" smd roundrect
			(at -0.387 -1 270)
			(size 0.25 0.55)
			(layers "F.Cu" "F.Mask" "F.Paste")
			(roundrect_rratio 0.25)
			(net 532 "/Backplane/PCIe_{x2}.RX0+")
			(pintype "passive")
			(teardrops
				(best_length_ratio 0.2)
				(max_length 1)
				(best_width_ratio 0.9)
				(max_width 2)
				(curved_edges yes)
				(filter_ratio 0.9)
				(enabled yes)
				(allow_two_segments yes)
				(prefer_zone_connections yes)
			)
		)
		(pad "2" smd roundrect
			(at -0.387 -0.5 270)
			(size 0.25 0.55)
			(layers "F.Cu" "F.Mask" "F.Paste")
			(roundrect_rratio 0.25)
			(net 537 "/Backplane/PCIe_{x2}.RX0-")
			(pintype "passive")
			(teardrops
				(best_length_ratio 0.2)
				(max_length 1)
				(best_width_ratio 0.9)
				(max_width 2)
				(curved_edges yes)
				(filter_ratio 0.9)
				(enabled yes)
				(allow_two_segments yes)
				(prefer_zone_connections yes)
			)
		)
		(pad "3" smd roundrect
			(at -0.387 0 270)
			(size 0.4 0.55)
			(layers "F.Cu" "F.Mask" "F.Paste")
			(roundrect_rratio 0.25)
			(net 1 "GND")
			(pintype "power_in")
			(teardrops
				(best_length_ratio 0.2)
				(max_length 1)
				(best_width_ratio 0.9)
				(max_width 2)
				(curved_edges yes)
				(filter_ratio 0.9)
				(enabled yes)
				(allow_two_segments yes)
				(prefer_zone_connections yes)
			)
		)
		(pad "4" smd roundrect
			(at -0.387 0.498 270)
			(size 0.25 0.55)
			(layers "F.Cu" "F.Mask" "F.Paste")
			(roundrect_rratio 0.25)
			(net 771 "/Backplane/PCIe_{x2}.RX1+")
			(pintype "passive")
			(teardrops
				(best_length_ratio 0.2)
				(max_length 1)
				(best_width_ratio 0.9)
				(max_width 2)
				(curved_edges yes)
				(filter_ratio 0.9)
				(enabled yes)
				(allow_two_segments yes)
				(prefer_zone_connections yes)
			)
		)
		(pad "5" smd roundrect
			(at -0.387 0.998 270)
			(size 0.25 0.55)
			(layers "F.Cu" "F.Mask" "F.Paste")
			(roundrect_rratio 0.25)
			(net 772 "/Backplane/PCIe_{x2}.RX1-")
			(pintype "passive")
			(teardrops
				(best_length_ratio 0.2)
				(max_length 1)
				(best_width_ratio 0.9)
				(max_width 2)
				(curved_edges yes)
				(filter_ratio 0.9)
				(enabled yes)
				(allow_two_segments yes)
				(prefer_zone_connections yes)
			)
		)
		(pad "6" smd roundrect
			(at 0.385 0.998 270)
			(size 0.25 0.55)
			(layers "F.Cu" "F.Mask" "F.Paste")
			(roundrect_rratio 0.25)
			(net 772 "/Backplane/PCIe_{x2}.RX1-")
			(pintype "passive")
			(teardrops
				(best_length_ratio 0.2)
				(max_length 1)
				(best_width_ratio 0.9)
				(max_width 2)
				(curved_edges yes)
				(filter_ratio 0.9)
				(enabled yes)
				(allow_two_segments yes)
				(prefer_zone_connections yes)
			)
		)
		(pad "7" smd roundrect
			(at 0.385 0.498 270)
			(size 0.25 0.55)
			(layers "F.Cu" "F.Mask" "F.Paste")
			(roundrect_rratio 0.25)
			(net 771 "/Backplane/PCIe_{x2}.RX1+")
			(pintype "passive")
			(teardrops
				(best_length_ratio 0.2)
				(max_length 1)
				(best_width_ratio 0.9)
				(max_width 2)
				(curved_edges yes)
				(filter_ratio 0.9)
				(enabled yes)
				(allow_two_segments yes)
				(prefer_zone_connections yes)
			)
		)
		(pad "8" smd roundrect
			(at 0.385 0 270)
			(size 0.4 0.55)
			(layers "F.Cu" "F.Mask" "F.Paste")
			(roundrect_rratio 0.25)
			(net 1 "GND")
			(pintype "passive")
			(teardrops
				(best_length_ratio 0.2)
				(max_length 1)
				(best_width_ratio 0.9)
				(max_width 2)
				(curved_edges yes)
				(filter_ratio 0.9)
				(enabled yes)
				(allow_two_segments yes)
				(prefer_zone_connections yes)
			)
		)
		(pad "9" smd roundrect
			(at 0.385 -0.5 270)
			(size 0.25 0.55)
			(layers "F.Cu" "F.Mask" "F.Paste")
			(roundrect_rratio 0.25)
			(net 537 "/Backplane/PCIe_{x2}.RX0-")
			(pintype "passive")
			(teardrops
				(best_length_ratio 0.2)
				(max_length 1)
				(best_width_ratio 0.9)
				(max_width 2)
				(curved_edges yes)
				(filter_ratio 0.9)
				(enabled yes)
				(allow_two_segments yes)
				(prefer_zone_connections yes)
			)
		)
		(pad "10" smd roundrect
			(at 0.385 -1 270)
			(size 0.25 0.55)
			(layers "F.Cu" "F.Mask" "F.Paste")
			(roundrect_rratio 0.25)
			(net 532 "/Backplane/PCIe_{x2}.RX0+")
			(pintype "passive")
			(teardrops
				(best_length_ratio 0.2)
				(max_length 1)
				(best_width_ratio 0.9)
				(max_width 2)
				(curved_edges yes)
				(filter_ratio 0.9)
				(enabled yes)
				(allow_two_segments yes)
				(prefer_zone_connections yes)
			)
		)
	)
)
